# S9S_MB_2U (Grand Teton) — schematic netlist excerpt (pin names and nets, part order shuffled) for the footprints in the layout excerpt that follows; sources: Cadence DE-HDL packaged netlist, KiCad conversion of 03242023_DA0F0TMBIJ0_F0T_Motherboard_J_brd_V01_OCP.brd

C1894  Q_CAP  0.01UF 50V 10% X7R  pkg C0402  page 217 : A = P3V3_AUX_FPGA_VCCIO2 ; B = GND
C1300  Q_CAP  1000PF 50V 5% EMPTY  pkg 0402  page 281 : A = FM_PVPP_HBM_CPU0_EN ; B = GND

(kicad_pcb
	(version 20260206)
	(generator "pcbnew")
	(generator_version "10.0")
	(general
		(thickness 1.6)
		(legacy_teardrops no)
	)
	(paper "A4")
	(title_block
		(title "03242023_DA0F0TMBIJ0_F0T_Motherboard_J_brd_V01_OCP.brd")
		(comment 1 "Grand Teton / footprints 5076-5077 of 6105")
	)
	(layers
		(0 "F.Cu" signal "TOP")
		(4 "In1.Cu" signal "GND")
		(6 "In2.Cu" signal "IN1")
		(8 "In3.Cu" signal "GND1")
		(10 "In4.Cu" signal "IN2")
		(12 "In5.Cu" signal "GND2")
		(14 "In6.Cu" signal "IN3")
		(16 "In7.Cu" signal "GND3")
		(18 "In8.Cu" signal "VCC")
		(20 "In9.Cu" signal "VCC1")
		(22 "In10.Cu" signal "GND4")
		(24 "In11.Cu" signal "IN4")
		(26 "In12.Cu" signal "GND5")
		(28 "In13.Cu" signal "IN5")
		(30 "In14.Cu" signal "GND6")
		(32 "In15.Cu" signal "IN6")
		(34 "In16.Cu" signal "GND7")
		(2 "B.Cu" signal "BOTTOM")
		(9 "F.Adhes" user "F.Adhesive")
		(11 "B.Adhes" user "B.Adhesive")
		(13 "F.Paste" user "Package Geometry/Pastemask Top")
		(15 "B.Paste" user "Package Geometry/Pastemask Bottom")
		(5 "F.SilkS" user "Ref Des/Silkscreen Top")
		(7 "B.SilkS" user "Ref Des/Silkscreen Bottom")
		(1 "F.Mask" user "Board Geometry/Soldermask Top")
		(3 "B.Mask" user "Board Geometry/Soldermask Bottom")
		(17 "Dwgs.User" user "User.Drawings")
		(19 "Cmts.User" user "User.Comments")
		(21 "Eco1.User" user "User.Eco1")
		(23 "Eco2.User" user "User.Eco2")
		(25 "Edge.Cuts" user "Board Geometry/Outline")
		(27 "Margin" user)
		(31 "F.CrtYd" user "Package Geometry/Place Bound Top")
		(29 "B.CrtYd" user "Package Geometry/Place Bound Bottom")
		(35 "F.Fab" user "Ref Des/Assembly Top")
		(33 "B.Fab" user "Ref Des/Assembly Bottom")
	)
	(footprint ""
		(layer "B.Cu")
		(at 185.755788 -116.975382 180)
		(property "Reference" "C1894"
			(at 0 0 0)
			(layer "B.SilkS")
			(hide yes)
			(effects
				(font
					(size 1.27 1.27)
				)
				(justify mirror)
			)
		)
		(property "Value" ""
			(at 0 0 0)
			(layer "B.Fab")
			(effects
				(font
					(size 1.27 1.27)
				)
				(justify mirror)
			)
		)
		(duplicate_pad_numbers_are_jumpers no)
		(fp_line
			(start 0.69215 0.2921)
			(end 0.69215 -0.2921)
			(stroke
				(width 0.1524)
				(type default)
			)
			(layer "B.SilkS")
		)
		(fp_line
			(start 0.69215 -0.2921)
			(end -0.69215 -0.2921)
			(stroke
				(width 0.1524)
				(type default)
			)
			(layer "B.SilkS")
		)
		(fp_line
			(start -0.69215 0.2921)
			(end 0.69215 0.2921)
			(stroke
				(width 0.1524)
				(type default)
			)
			(layer "B.SilkS")
		)
		(fp_line
			(start -0.69215 -0.2921)
			(end -0.69215 0.2921)
			(stroke
				(width 0.1524)
				(type default)
			)
			(layer "B.SilkS")
		)
		(fp_line
			(start 0.51435 0.2794)
			(end 0.51435 -0.2794)
			(stroke
				(width 0.1)
				(type default)
			)
			(layer "B.Fab")
		)
		(fp_line
			(start 0.51435 -0.2794)
			(end -0.51435 -0.2794)
			(stroke
				(width 0.1)
				(type default)
			)
			(layer "B.Fab")
		)
		(fp_line
			(start -0.51435 0.2794)
			(end 0.51435 0.2794)
			(stroke
				(width 0.1)
				(type default)
			)
			(layer "B.Fab")
		)
		(fp_line
			(start -0.51435 -0.2794)
			(end -0.51435 0.2794)
			(stroke
				(width 0.1)
				(type default)
			)
			(layer "B.Fab")
		)
		(pad "1" smd circle
			(at 0.40005 0)
			(size 0 0)
			(layers "B.Cu" "B.Mask" "B.Paste")
			(net "P3V3_AUX_FPGA_VCCIO2")
		)
		(pad "2" smd circle
			(at -0.40005 0)
			(size 0 0)
			(layers "B.Cu" "B.Mask" "B.Paste")
			(net "GND")
		)
		(zone
			(layer "B.Cu")
			(hatch none 0.5)
			(connect_pads
				(clearance 0)
			)
			(min_thickness 0.25)
			(keepout
				(tracks not_allowed)
				(vias allowed)
				(pads allowed)
				(copperpour not_allowed)
				(footprints allowed)
			)
			(placement
				(enabled no)
				(sheetname "")
			)
			(fill
				(thermal_gap 0.5)
				(thermal_bridge_width 0.5)
				(island_removal_mode 0)
			)
			(polygon
				(pts
					(xy 185.565288 -117.063012) (xy 185.656728 -117.121178) (xy 185.856118 -117.121178) (xy 185.946288 -117.063012)
					(xy 185.946288 -116.887752) (xy 185.856118 -116.829332) (xy 185.656728 -116.829332) (xy 185.565288 -116.887498)
				)
			)
		)
	)
	(footprint ""
		(layer "B.Cu")
		(at 371.665246 -354.93833 90)
		(property "Reference" "C1300"
			(at 0 0 90)
			(layer "B.SilkS")
			(hide yes)
			(effects
				(font
					(size 1.27 1.27)
				)
				(justify mirror)
			)
		)
		(property "Value" ""
			(at 0 0 90)
			(layer "B.Fab")
			(effects
				(font
					(size 1.27 1.27)
				)
				(justify mirror)
			)
		)
		(duplicate_pad_numbers_are_jumpers no)
		(fp_line
			(start 0.7874 -0.4064)
			(end -0.7874 -0.4064)
			(stroke
				(width 0.1524)
				(type default)
			)
			(layer "B.SilkS")
		)
		(fp_line
			(start -0.7874 -0.4064)
			(end -0.7874 0.4064)
			(stroke
				(width 0.1524)
				(type default)
			)
			(layer "B.SilkS")
		)
		(fp_line
			(start 0.7874 0.4064)
			(end 0.7874 -0.4064)
			(stroke
				(width 0.1524)
				(type default)
			)
			(layer "B.SilkS")
		)
		(fp_line
			(start -0.7874 0.4064)
			(end 0.7874 0.4064)
			(stroke
				(width 0.1524)
				(type default)
			)
			(layer "B.SilkS")
		)
		(fp_line
			(start 0.67945 -0.305054)
			(end 0.12065 -0.305054)
			(stroke
				(width 0.1)
				(type default)
			)
			(layer "B.Fab")
		)
		(fp_line
			(start 0.12065 -0.305054)
			(end 0.12065 -0.2794)
			(stroke
				(width 0.1)
				(type default)
			)
			(layer "B.Fab")
		)
		(fp_line
			(start -0.12065 -0.3048)
			(end -0.67945 -0.3048)
			(stroke
				(width 0.1)
				(type default)
			)
			(layer "B.Fab")
		)
		(fp_line
			(start -0.67945 -0.3048)
			(end -0.67945 0.3048)
			(stroke
				(width 0.1)
				(type default)
			)
			(layer "B.Fab")
		)
		(fp_line
			(start 0.12065 -0.2794)
			(end -0.12065 -0.2794)
			(stroke
				(width 0.1)
				(type default)
			)
			(layer "B.Fab")
		)
		(fp_line
			(start -0.12065 -0.2794)
			(end -0.12065 -0.3048)
			(stroke
				(width 0.1)
				(type default)
			)
			(layer "B.Fab")
		)
		(fp_line
			(start 0.12065 0.2794)
			(end 0.12065 0.3048)
			(stroke
				(width 0.1)
				(type default)
			)
			(layer "B.Fab")
		)
		(fp_line
			(start -0.120396 0.2794)
			(end 0.12065 0.2794)
			(stroke
				(width 0.1)
				(type default)
			)
			(layer "B.Fab")
		)
		(fp_line
			(start 0.67945 0.3048)
			(end 0.67945 -0.305054)
			(stroke
				(width 0.1)
				(type default)
			)
			(layer "B.Fab")
		)
		(fp_line
			(start 0.12065 0.3048)
			(end 0.67945 0.3048)
			(stroke
				(width 0.1)
				(type default)
			)
			(layer "B.Fab")
		)
		(fp_line
			(start -0.120396 0.3048)
			(end -0.120396 0.2794)
			(stroke
				(width 0.1)
				(type default)
			)
			(layer "B.Fab")
		)
		(fp_line
			(start -0.67945 0.3048)
			(end -0.120396 0.3048)
			(stroke
				(width 0.1)
				(type default)
			)
			(layer "B.Fab")
		)
		(pad "1" smd circle
			(at 0.40005 0 270)
			(size 0 0)
			(layers "B.Cu" "B.Mask" "B.Paste")
			(net "FM_PVPP_HBM_CPU0_EN")
		)
		(pad "2" smd circle
			(at -0.40005 0 270)
			(size 0 0)
			(layers "B.Cu" "B.Mask" "B.Paste")
			(net "GND")
		)
	)
)
